# T6G (Grand Teton) — schematic netlist excerpt (pin names and nets, part order shuffled) for the footprints in the layout excerpt that follows; sources: Cadence DE-HDL packaged netlist, KiCad conversion of 04192023_DAF0TMB3IC0_F0TG_MB_C_brd_V02_OCP.brd

C622  Q_CAP  1UF 4V 20% X6S  pkg 0201  page 290 : A = P0V9_CPU0_RT1_2A ; B = GND
C3888  Q_CAP  22UF 4V 20% X6S  pkg C0402  page 68 : A = PVDDCR_SOC_P0 ; B = GND
R8108  Q_RES  160K 1% EMPTY  pkg 0402LF  page 267 : A = HSC_CSOUT ; B = HSC_OC_VOL

(kicad_pcb
	(version 20260206)
	(generator "pcbnew")
	(generator_version "10.0")
	(general
		(thickness 1.6)
		(legacy_teardrops no)
	)
	(paper "A4")
	(title_block
		(title "04192023_DAF0TMB3IC0_F0TG_MB_C_brd_V02_OCP.brd")
		(comment 1 "Grand Teton / footprints 5652-5654 of 8354")
	)
	(layers
		(0 "F.Cu" signal "TOP")
		(4 "In1.Cu" signal "GND")
		(6 "In2.Cu" signal "IN1")
		(8 "In3.Cu" signal "GND1")
		(10 "In4.Cu" signal "IN2")
		(12 "In5.Cu" signal "GND2")
		(14 "In6.Cu" signal "IN3")
		(16 "In7.Cu" signal "GND3")
		(18 "In8.Cu" signal "VCC")
		(20 "In9.Cu" signal "VCC1")
		(22 "In10.Cu" signal "GND4")
		(24 "In11.Cu" signal "IN4")
		(26 "In12.Cu" signal "GND5")
		(28 "In13.Cu" signal "IN5")
		(30 "In14.Cu" signal "GND6")
		(32 "In15.Cu" signal "IN6")
		(34 "In16.Cu" signal "GND7")
		(2 "B.Cu" signal "BOTTOM")
		(9 "F.Adhes" user "F.Adhesive")
		(11 "B.Adhes" user "B.Adhesive")
		(13 "F.Paste" user "Package Geometry/Pastemask Top")
		(15 "B.Paste" user "Package Geometry/Pastemask Bottom")
		(5 "F.SilkS" user "Ref Des/Silkscreen Top")
		(7 "B.SilkS" user "Ref Des/Silkscreen Bottom")
		(1 "F.Mask" user "Board Geometry/Soldermask Top")
		(3 "B.Mask" user "Board Geometry/Soldermask Bottom")
		(17 "Dwgs.User" user "User.Drawings")
		(19 "Cmts.User" user "User.Comments")
		(21 "Eco1.User" user "User.Eco1")
		(23 "Eco2.User" user "User.Eco2")
		(25 "Edge.Cuts" user "Board Geometry/Outline")
		(27 "Margin" user)
		(31 "F.CrtYd" user "Package Geometry/Place Bound Top")
		(29 "B.CrtYd" user "Package Geometry/Place Bound Bottom")
		(35 "F.Fab" user "Ref Des/Assembly Top")
		(33 "B.Fab" user "Ref Des/Assembly Bottom")
	)
	(footprint ""
		(layer "B.Cu")
		(at 361.046014 -257.744976 180)
		(property "Reference" "C3888"
			(at 0 0 0)
			(layer "B.SilkS")
			(hide yes)
			(effects
				(font
					(size 1.27 1.27)
				)
				(justify mirror)
			)
		)
		(property "Value" ""
			(at 0 0 0)
			(layer "B.Fab")
			(effects
				(font
					(size 1.27 1.27)
				)
				(justify mirror)
			)
		)
		(duplicate_pad_numbers_are_jumpers no)
		(fp_line
			(start 0.7874 0.4064)
			(end 0.7874 -0.4064)
			(stroke
				(width 0.1524)
				(type default)
			)
			(layer "B.SilkS")
		)
		(fp_line
			(start 0.7874 -0.4064)
			(end -0.7874 -0.4064)
			(stroke
				(width 0.1524)
				(type default)
			)
			(layer "B.SilkS")
		)
		(fp_line
			(start -0.7874 0.4064)
			(end 0.7874 0.4064)
			(stroke
				(width 0.1524)
				(type default)
			)
			(layer "B.SilkS")
		)
		(fp_line
			(start -0.7874 -0.4064)
			(end -0.7874 0.4064)
			(stroke
				(width 0.1524)
				(type default)
			)
			(layer "B.SilkS")
		)
		(fp_line
			(start 0.67945 0.3048)
			(end 0.67945 -0.305054)
			(stroke
				(width 0.1)
				(type default)
			)
			(layer "B.Fab")
		)
		(fp_line
			(start 0.67945 -0.305054)
			(end 0.12065 -0.305054)
			(stroke
				(width 0.1)
				(type default)
			)
			(layer "B.Fab")
		)
		(fp_line
			(start 0.12065 0.3048)
			(end 0.67945 0.3048)
			(stroke
				(width 0.1)
				(type default)
			)
			(layer "B.Fab")
		)
		(fp_line
			(start 0.12065 0.2794)
			(end 0.12065 0.3048)
			(stroke
				(width 0.1)
				(type default)
			)
			(layer "B.Fab")
		)
		(fp_line
			(start 0.12065 -0.2794)
			(end -0.12065 -0.2794)
			(stroke
				(width 0.1)
				(type default)
			)
			(layer "B.Fab")
		)
		(fp_line
			(start 0.12065 -0.305054)
			(end 0.12065 -0.2794)
			(stroke
				(width 0.1)
				(type default)
			)
			(layer "B.Fab")
		)
		(fp_line
			(start -0.120396 0.3048)
			(end -0.120396 0.2794)
			(stroke
				(width 0.1)
				(type default)
			)
			(layer "B.Fab")
		)
		(fp_line
			(start -0.120396 0.2794)
			(end 0.12065 0.2794)
			(stroke
				(width 0.1)
				(type default)
			)
			(layer "B.Fab")
		)
		(fp_line
			(start -0.12065 -0.2794)
			(end -0.12065 -0.3048)
			(stroke
				(width 0.1)
				(type default)
			)
			(layer "B.Fab")
		)
		(fp_line
			(start -0.12065 -0.3048)
			(end -0.67945 -0.3048)
			(stroke
				(width 0.1)
				(type default)
			)
			(layer "B.Fab")
		)
		(fp_line
			(start -0.67945 0.3048)
			(end -0.120396 0.3048)
			(stroke
				(width 0.1)
				(type default)
			)
			(layer "B.Fab")
		)
		(fp_line
			(start -0.67945 -0.3048)
			(end -0.67945 0.3048)
			(stroke
				(width 0.1)
				(type default)
			)
			(layer "B.Fab")
		)
		(pad "1" smd circle
			(at 0.40005 0)
			(size 0 0)
			(layers "B.Cu" "B.Mask" "B.Paste")
			(net "PVDDCR_SOC_P0")
		)
		(pad "2" smd circle
			(at -0.40005 0)
			(size 0 0)
			(layers "B.Cu" "B.Mask" "B.Paste")
			(net "GND")
		)
	)
	(footprint ""
		(layer "B.Cu")
		(at 183.54802 -423.011092 90)
		(property "Reference" "R8108"
			(at 0 0 90)
			(layer "B.SilkS")
			(hide yes)
			(effects
				(font
					(size 1.27 1.27)
				)
				(justify mirror)
			)
		)
		(property "Value" ""
			(at 0 0 90)
			(layer "B.Fab")
			(effects
				(font
					(size 1.27 1.27)
				)
				(justify mirror)
			)
		)
		(duplicate_pad_numbers_are_jumpers no)
		(fp_line
			(start 0.7874 -0.4064)
			(end -0.7874 -0.4064)
			(stroke
				(width 0.1524)
				(type default)
			)
			(layer "B.SilkS")
		)
		(fp_line
			(start -0.7874 -0.4064)
			(end -0.7874 0.4064)
			(stroke
				(width 0.1524)
				(type default)
			)
			(layer "B.SilkS")
		)
		(fp_line
			(start 0.7874 0.4064)
			(end 0.7874 -0.4064)
			(stroke
				(width 0.1524)
				(type default)
			)
			(layer "B.SilkS")
		)
		(fp_line
			(start -0.7874 0.4064)
			(end 0.7874 0.4064)
			(stroke
				(width 0.1524)
				(type default)
			)
			(layer "B.SilkS")
		)
		(fp_line
			(start 0.67945 -0.305054)
			(end 0.12065 -0.305054)
			(stroke
				(width 0.1)
				(type default)
			)
			(layer "B.Fab")
		)
		(fp_line
			(start 0.12065 -0.305054)
			(end 0.12065 -0.2794)
			(stroke
				(width 0.1)
				(type default)
			)
			(layer "B.Fab")
		)
		(fp_line
			(start -0.12065 -0.3048)
			(end -0.67945 -0.3048)
			(stroke
				(width 0.1)
				(type default)
			)
			(layer "B.Fab")
		)
		(fp_line
			(start -0.67945 -0.3048)
			(end -0.67945 0.3048)
			(stroke
				(width 0.1)
				(type default)
			)
			(layer "B.Fab")
		)
		(fp_line
			(start 0.12065 -0.2794)
			(end -0.12065 -0.2794)
			(stroke
				(width 0.1)
				(type default)
			)
			(layer "B.Fab")
		)
		(fp_line
			(start -0.12065 -0.2794)
			(end -0.12065 -0.3048)
			(stroke
				(width 0.1)
				(type default)
			)
			(layer "B.Fab")
		)
		(fp_line
			(start 0.12065 0.2794)
			(end 0.12065 0.3048)
			(stroke
				(width 0.1)
				(type default)
			)
			(layer "B.Fab")
		)
		(fp_line
			(start -0.120396 0.2794)
			(end 0.12065 0.2794)
			(stroke
				(width 0.1)
				(type default)
			)
			(layer "B.Fab")
		)
		(fp_line
			(start 0.67945 0.3048)
			(end 0.67945 -0.305054)
			(stroke
				(width 0.1)
				(type default)
			)
			(layer "B.Fab")
		)
		(fp_line
			(start 0.12065 0.3048)
			(end 0.67945 0.3048)
			(stroke
				(width 0.1)
				(type default)
			)
			(layer "B.Fab")
		)
		(fp_line
			(start -0.120396 0.3048)
			(end -0.120396 0.2794)
			(stroke
				(width 0.1)
				(type default)
			)
			(layer "B.Fab")
		)
		(fp_line
			(start -0.67945 0.3048)
			(end -0.120396 0.3048)
			(stroke
				(width 0.1)
				(type default)
			)
			(layer "B.Fab")
		)
		(pad "1" smd circle
			(at 0.40005 0 270)
			(size 0 0)
			(layers "B.Cu" "B.Mask" "B.Paste")
			(net "HSC_CSOUT")
		)
		(pad "2" smd circle
			(at -0.40005 0 270)
			(size 0 0)
			(layers "B.Cu" "B.Mask" "B.Paste")
			(net "HSC_OC_VOL")
		)
	)
	(footprint ""
		(layer "B.Cu")
		(at 335.70037 -393.88288 -90)
		(property "Reference" "C622"
			(at 0 0 90)
			(layer "B.SilkS")
			(hide yes)
			(effects
				(font
					(size 1.27 1.27)
				)
				(justify mirror)
			)
		)
		(property "Value" ""
			(at 0 0 90)
			(layer "B.Fab")
			(effects
				(font
					(size 1.27 1.27)
				)
				(justify mirror)
			)
		)
		(duplicate_pad_numbers_are_jumpers no)
		(fp_line
			(start -0.299974 0.150114)
			(end 0.299974 0.150114)
			(stroke
				(width 0.1)
				(type default)
			)
			(layer "B.Fab")
		)
		(fp_line
			(start 0.299974 0.150114)
			(end 0.299974 -0.150114)
			(stroke
				(width 0.1)
				(type default)
			)
			(layer "B.Fab")
		)
		(fp_line
			(start -0.299974 -0.150114)
			(end -0.299974 0.150114)
			(stroke
				(width 0.1)
				(type default)
			)
			(layer "B.Fab")
		)
		(fp_line
			(start 0.299974 -0.150114)
			(end -0.299974 -0.150114)
			(stroke
				(width 0.1)
				(type default)
			)
			(layer "B.Fab")
		)
		(pad "1" smd rect
			(at 0.2667 0 90)
			(size 0.3048 0.381)
			(layers "B.Cu" "B.Mask" "B.Paste")
			(net "P0V9_CPU0_RT1_2A")
		)
		(pad "2" smd rect
			(at -0.2667 0 90)
			(size 0.3048 0.381)
			(layers "B.Cu" "B.Mask" "B.Paste")
			(net "GND")
		)
	)
)
